(kicad_pcb
	(version 20260206)
	(generator "pcbnew")
	(generator_version "10.0")
	(general
		(thickness 1.6)
		(legacy_teardrops no)
	)
	(paper "A4")
	(title_block
		(title "Bryce Canyon_SCC_16316-1_OCP.brd")
		(comment 1 "Bryce Canyon / footprints 749-758 of 1561")
	)
	(layers
		(0 "F.Cu" signal "TOP")
		(4 "In1.Cu" signal "L2GND")
		(6 "In2.Cu" signal "L3")
		(8 "In3.Cu" signal "L4VCC")
		(10 "In4.Cu" signal "L5VCC")
		(12 "In5.Cu" signal "L6")
		(14 "In6.Cu" signal "L7GND")
		(2 "B.Cu" signal "BOTTOM")
		(9 "F.Adhes" user "F.Adhesive")
		(11 "B.Adhes" user "B.Adhesive")
		(13 "F.Paste" user "Package Geometry/Pastemask Top")
		(15 "B.Paste" user "Package Geometry/Pastemask Bottom")
		(5 "F.SilkS" user "Ref Des/Silkscreen Top")
		(7 "B.SilkS" user "Ref Des/Silkscreen Bottom")
		(1 "F.Mask" user "Board Geometry/Soldermask Top")
		(3 "B.Mask" user "Board Geometry/Soldermask Bottom")
		(17 "Dwgs.User" user "User.Drawings")
		(19 "Cmts.User" user "User.Comments")
		(21 "Eco1.User" user "User.Eco1")
		(23 "Eco2.User" user "User.Eco2")
		(25 "Edge.Cuts" user "Board Geometry/Outline")
		(27 "Margin" user)
		(31 "F.CrtYd" user "Package Geometry/Place Bound Top")
		(29 "B.CrtYd" user "Package Geometry/Place Bound Bottom")
		(35 "F.Fab" user "Ref Des/Assembly Top")
		(33 "B.Fab" user "Ref Des/Assembly Bottom")
	)
	(footprint ""
		(layer "F.Cu")
		(at 121.031 -86.995)
		(property "Reference" "R83"
			(at 0 0 0)
			(layer "F.SilkS")
			(hide yes)
			(effects
				(font
					(size 1.27 1.27)
				)
			)
		)
		(property "Value" "4K7R2F-GP"
			(at 0.064008 -3.993896 0)
			(unlocked yes)
			(layer "F.Fab")
			(hide yes)
			(effects
				(font
					(size 1.016 1.016)
					(thickness 0.1524)
				)
			)
		)
		(property "Device Type" "R402H16"
			(at 0.064008 -5.517896 0)
			(unlocked yes)
			(layer "F.Fab")
			(hide yes)
			(effects
				(font
					(size 1.016 1.016)
					(thickness 0.1524)
				)
			)
		)
		(duplicate_pad_numbers_are_jumpers no)
		(fp_line
			(start -0.508 -0.9398)
			(end -0.508 0.9398)
			(stroke
				(width 0.1524)
				(type default)
			)
			(layer "F.SilkS")
		)
		(fp_line
			(start 0.508 -0.9398)
			(end -0.508 -0.9398)
			(stroke
				(width 0.1524)
				(type default)
			)
			(layer "F.SilkS")
		)
		(fp_rect
			(start -0.508 0.9398)
			(end 0.508 -0.9398)
			(stroke
				(width 0)
				(type default)
			)
			(fill no)
			(layer "F.CrtYd")
		)
		(fp_rect
			(start -0.508 0.9398)
			(end 0.508 -0.9398)
			(stroke
				(width 0)
				(type default)
			)
			(fill no)
			(layer "F.Fab")
		)
		(pad "1" smd custom
			(at 0 -0.4445)
			(size 0.1397 0.1397)
			(layers "F.Cu" "F.Mask" "F.Paste")
			(net "P1V8_E")
			(options
				(clearance outline)
				(anchor circle)
			)
			(primitives
				(gr_poly
					(pts
						(arc
							(start -0.1778 -0.2794)
							(mid -0.249642 -0.249642)
							(end -0.2794 -0.1778)
						)
						(arc
							(start -0.2794 0.1778)
							(mid -0.249642 0.249642)
							(end -0.1778 0.2794)
						)
						(arc
							(start 0.1778 0.2794)
							(mid 0.249642 0.249642)
							(end 0.2794 0.1778)
						)
						(arc
							(start 0.2794 -0.1778)
							(mid 0.249642 -0.249642)
							(end 0.1778 -0.2794)
						)
					)
					(width 0)
					(fill yes)
				)
			)
		)
		(pad "2" smd custom
			(at 0 0.4445)
			(size 0.1397 0.1397)
			(layers "F.Cu" "F.Mask" "F.Paste")
			(net "SCC_TYPE_3_LS")
			(options
				(clearance outline)
				(anchor circle)
			)
			(primitives
				(gr_poly
					(pts
						(arc
							(start -0.1778 -0.2794)
							(mid -0.249642 -0.249642)
							(end -0.2794 -0.1778)
						)
						(arc
							(start -0.2794 0.1778)
							(mid -0.249642 0.249642)
							(end -0.1778 0.2794)
						)
						(arc
							(start 0.1778 0.2794)
							(mid 0.249642 0.249642)
							(end 0.2794 0.1778)
						)
						(arc
							(start 0.2794 -0.1778)
							(mid 0.249642 -0.249642)
							(end 0.1778 -0.2794)
						)
					)
					(width 0)
					(fill yes)
				)
			)
		)
	)
	(footprint ""
		(layer "F.Cu")
		(at 162.961066 -56.32958)
		(property "Reference" "TP120"
			(at 0 0 0)
			(layer "F.SilkS")
			(hide yes)
			(effects
				(font
					(size 1.27 1.27)
				)
			)
		)
		(property "Value" "TPAD28-2-GP"
			(at -0.0127 -1.6637 0)
			(unlocked yes)
			(layer "F.Fab")
			(hide yes)
			(effects
				(font
					(size 1.016 1.016)
					(thickness 0.1524)
				)
			)
		)
		(property "Device Type" "TPAD28"
			(at -0.0127 -3.1877 0)
			(unlocked yes)
			(layer "F.Fab")
			(hide yes)
			(effects
				(font
					(size 1.016 1.016)
					(thickness 0.1524)
				)
			)
		)
		(duplicate_pad_numbers_are_jumpers no)
		(fp_poly
			(pts
				(arc
					(start 0.3556 0)
					(mid -0.3556 0)
					(end 0.3556 0)
				)
			)
			(stroke
				(width 0)
				(type default)
			)
			(fill no)
			(layer "F.CrtYd")
		)
		(fp_poly
			(pts
				(arc
					(start 0.6096 0)
					(mid -0.6096 0)
					(end 0.6096 0)
				)
			)
			(stroke
				(width 0)
				(type default)
			)
			(fill no)
			(layer "F.Fab")
		)
		(pad "1" smd circle
			(at 0 0)
			(size 0.7112 0.7112)
			(layers "F.Cu" "F.Mask" "F.Paste")
			(net "ICE0_TMS")
		)
	)
	(footprint ""
		(layer "F.Cu")
		(at 178.181 -55.626)
		(property "Reference" "TP135"
			(at 0 0 0)
			(layer "F.SilkS")
			(hide yes)
			(effects
				(font
					(size 1.27 1.27)
				)
			)
		)
		(property "Value" "TPAD28-2-GP"
			(at -0.0127 -1.6637 0)
			(unlocked yes)
			(layer "F.Fab")
			(hide yes)
			(effects
				(font
					(size 1.016 1.016)
					(thickness 0.1524)
				)
			)
		)
		(property "Device Type" "TPAD28"
			(at -0.0127 -3.1877 0)
			(unlocked yes)
			(layer "F.Fab")
			(hide yes)
			(effects
				(font
					(size 1.016 1.016)
					(thickness 0.1524)
				)
			)
		)
		(duplicate_pad_numbers_are_jumpers no)
		(fp_poly
			(pts
				(arc
					(start 0.3556 0)
					(mid -0.3556 0)
					(end 0.3556 0)
				)
			)
			(stroke
				(width 0)
				(type default)
			)
			(fill no)
			(layer "F.CrtYd")
		)
		(fp_poly
			(pts
				(arc
					(start 0.6096 0)
					(mid -0.6096 0)
					(end 0.6096 0)
				)
			)
			(stroke
				(width 0)
				(type default)
			)
			(fill no)
			(layer "F.Fab")
		)
		(pad "1" smd circle
			(at 0 0)
			(size 0.7112 0.7112)
			(layers "F.Cu" "F.Mask" "F.Paste")
			(net "JTAG_IOC_TMS")
		)
	)
	(footprint ""
		(layer "F.Cu")
		(at 152.164542 -95.23857 -90)
		(property "Reference" "R295"
			(at 0 0 270)
			(layer "F.SilkS")
			(hide yes)
			(effects
				(font
					(size 1.27 1.27)
				)
			)
		)
		(property "Value" "0R2J-2-GP"
			(at 0.064008 -3.993896 270)
			(unlocked yes)
			(layer "F.Fab")
			(hide yes)
			(effects
				(font
					(size 1.016 1.016)
					(thickness 0.1524)
				)
			)
		)
		(property "Device Type" "R402H16"
			(at 0.064008 -5.517896 270)
			(unlocked yes)
			(layer "F.Fab")
			(hide yes)
			(effects
				(font
					(size 1.016 1.016)
					(thickness 0.1524)
				)
			)
		)
		(duplicate_pad_numbers_are_jumpers no)
		(fp_line
			(start -0.508 -0.9398)
			(end -0.508 0.9398)
			(stroke
				(width 0.1524)
				(type default)
			)
			(layer "F.SilkS")
		)
		(fp_line
			(start 0.508 -0.9398)
			(end -0.508 -0.9398)
			(stroke
				(width 0.1524)
				(type default)
			)
			(layer "F.SilkS")
		)
		(fp_rect
			(start -0.508 0.9398)
			(end 0.508 -0.9398)
			(stroke
				(width 0)
				(type default)
			)
			(fill no)
			(layer "F.CrtYd")
		)
		(fp_rect
			(start -0.508 0.9398)
			(end 0.508 -0.9398)
			(stroke
				(width 0)
				(type default)
			)
			(fill no)
			(layer "F.Fab")
		)
		(pad "1" smd custom
			(at 0 -0.4445 270)
			(size 0.1397 0.1397)
			(layers "F.Cu" "F.Mask" "F.Paste")
			(net "SDB_TX_R")
			(options
				(clearance outline)
				(anchor circle)
			)
			(primitives
				(gr_poly
					(pts
						(arc
							(start -0.1778 -0.2794)
							(mid -0.249642 -0.249642)
							(end -0.2794 -0.1778)
						)
						(arc
							(start -0.2794 0.1778)
							(mid -0.249642 0.249642)
							(end -0.1778 0.2794)
						)
						(arc
							(start 0.1778 0.2794)
							(mid 0.249642 0.249642)
							(end 0.2794 0.1778)
						)
						(arc
							(start 0.2794 -0.1778)
							(mid 0.249642 -0.249642)
							(end 0.1778 -0.2794)
						)
					)
					(width 0)
					(fill yes)
				)
			)
		)
		(pad "2" smd custom
			(at 0 0.4445 270)
			(size 0.1397 0.1397)
			(layers "F.Cu" "F.Mask" "F.Paste")
			(net "SDB_TX")
			(options
				(clearance outline)
				(anchor circle)
			)
			(primitives
				(gr_poly
					(pts
						(arc
							(start -0.1778 -0.2794)
							(mid -0.249642 -0.249642)
							(end -0.2794 -0.1778)
						)
						(arc
							(start -0.2794 0.1778)
							(mid -0.249642 0.249642)
							(end -0.1778 0.2794)
						)
						(arc
							(start 0.1778 0.2794)
							(mid 0.249642 0.249642)
							(end 0.2794 0.1778)
						)
						(arc
							(start 0.2794 -0.1778)
							(mid 0.249642 -0.249642)
							(end 0.1778 -0.2794)
						)
					)
					(width 0)
					(fill yes)
				)
			)
		)
	)
	(footprint ""
		(layer "F.Cu")
		(at 193.167 -32.004 -90)
		(property "Reference" "TP89"
			(at 0 0 270)
			(layer "F.SilkS")
			(hide yes)
			(effects
				(font
					(size 1.27 1.27)
				)
			)
		)
		(property "Value" "TPAD28-2-GP"
			(at -0.0127 -1.6637 270)
			(unlocked yes)
			(layer "F.Fab")
			(hide yes)
			(effects
				(font
					(size 1.016 1.016)
					(thickness 0.1524)
				)
			)
		)
		(property "Device Type" "TPAD28"
			(at -0.0127 -3.1877 270)
			(unlocked yes)
			(layer "F.Fab")
			(hide yes)
			(effects
				(font
					(size 1.016 1.016)
					(thickness 0.1524)
				)
			)
		)
		(duplicate_pad_numbers_are_jumpers no)
		(fp_poly
			(pts
				(arc
					(start 0 -0.3556)
					(mid 0 0.3556)
					(end 0 -0.3556)
				)
			)
			(stroke
				(width 0)
				(type default)
			)
			(fill no)
			(layer "F.CrtYd")
		)
		(fp_poly
			(pts
				(arc
					(start 0 -0.6096)
					(mid 0 0.6096)
					(end 0 -0.6096)
				)
			)
			(stroke
				(width 0)
				(type default)
			)
			(fill no)
			(layer "F.Fab")
		)
		(pad "1" smd circle
			(at 0 0 270)
			(size 0.7112 0.7112)
			(layers "F.Cu" "F.Mask" "F.Paste")
			(net "IOC_GPIO_31")
		)
	)
	(footprint ""
		(layer "F.Cu")
		(at 136.2456 -81.1276 90)
		(property "Reference" "C677"
			(at 0 0 90)
			(layer "F.SilkS")
			(hide yes)
			(effects
				(font
					(size 1.27 1.27)
				)
			)
		)
		(property "Value" "SCD01U16V1KX-GP"
			(at -2.8321 -1.7399 90)
			(unlocked yes)
			(layer "F.Fab")
			(hide yes)
			(effects
				(font
					(size 1.016 1.016)
					(thickness 0.1524)
				)
			)
		)
		(property "Device Type" "C0201H13"
			(at -2.8321 -3.2639 90)
			(unlocked yes)
			(layer "F.Fab")
			(hide yes)
			(effects
				(font
					(size 1.016 1.016)
					(thickness 0.1524)
				)
			)
		)
		(duplicate_pad_numbers_are_jumpers no)
		(fp_rect
			(start -0.2794 0.6477)
			(end 0.2794 -0.6477)
			(stroke
				(width 0)
				(type default)
			)
			(fill no)
			(layer "F.CrtYd")
		)
		(fp_rect
			(start -0.2794 0.6477)
			(end 0.2794 -0.6477)
			(stroke
				(width 0)
				(type default)
			)
			(fill no)
			(layer "F.Fab")
		)
		(pad "1" smd custom
			(at 0 -0.2794 90)
			(size 0.0762 0.0762)
			(layers "F.Cu" "F.Mask" "F.Paste")
			(net "PHY_EXP_TO_CONN_C_11_DN")
			(options
				(clearance outline)
				(anchor circle)
			)
			(primitives
				(gr_poly
					(pts
						(arc
							(start 0.1524 -0.127)
							(mid 0.137521 -0.162921)
							(end 0.1016 -0.1778)
						)
						(arc
							(start -0.1016 -0.1778)
							(mid -0.137521 -0.162921)
							(end -0.1524 -0.127)
						)
						(arc
							(start -0.1524 0.127)
							(mid -0.137521 0.162921)
							(end -0.1016 0.1778)
						)
						(arc
							(start 0.1016 0.1778)
							(mid 0.137521 0.162921)
							(end 0.1524 0.127)
						)
					)
					(width 0)
					(fill yes)
				)
			)
		)
		(pad "2" smd custom
			(at 0 0.2794 90)
			(size 0.0762 0.0762)
			(layers "F.Cu" "F.Mask" "F.Paste")
			(net "PHY_EXP_TO_CONN_11_DN")
			(options
				(clearance outline)
				(anchor circle)
			)
			(primitives
				(gr_poly
					(pts
						(arc
							(start 0.1524 -0.127)
							(mid 0.137521 -0.162921)
							(end 0.1016 -0.1778)
						)
						(arc
							(start -0.1016 -0.1778)
							(mid -0.137521 -0.162921)
							(end -0.1524 -0.127)
						)
						(arc
							(start -0.1524 0.127)
							(mid -0.137521 0.162921)
							(end -0.1016 0.1778)
						)
						(arc
							(start 0.1016 0.1778)
							(mid 0.137521 0.162921)
							(end 0.1524 0.127)
						)
					)
					(width 0)
					(fill yes)
				)
			)
		)
	)
	(footprint ""
		(layer "F.Cu")
		(at 89.281 -78.232 -90)
		(property "Reference" "R461"
			(at 0 0 270)
			(layer "F.SilkS")
			(hide yes)
			(effects
				(font
					(size 1.27 1.27)
				)
			)
		)
		(property "Value" "0R2J-2-GP"
			(at 0.064008 -3.993896 270)
			(unlocked yes)
			(layer "F.Fab")
			(hide yes)
			(effects
				(font
					(size 1.016 1.016)
					(thickness 0.1524)
				)
			)
		)
		(property "Device Type" "R402H16"
			(at 0.064008 -5.517896 270)
			(unlocked yes)
			(layer "F.Fab")
			(hide yes)
			(effects
				(font
					(size 1.016 1.016)
					(thickness 0.1524)
				)
			)
		)
		(duplicate_pad_numbers_are_jumpers no)
		(fp_line
			(start -0.508 -0.9398)
			(end -0.508 0.9398)
			(stroke
				(width 0.1524)
				(type default)
			)
			(layer "F.SilkS")
		)
		(fp_line
			(start 0.508 -0.9398)
			(end -0.508 -0.9398)
			(stroke
				(width 0.1524)
				(type default)
			)
			(layer "F.SilkS")
		)
		(fp_rect
			(start -0.508 0.9398)
			(end 0.508 -0.9398)
			(stroke
				(width 0)
				(type default)
			)
			(fill no)
			(layer "F.CrtYd")
		)
		(fp_rect
			(start -0.508 0.9398)
			(end 0.508 -0.9398)
			(stroke
				(width 0)
				(type default)
			)
			(fill no)
			(layer "F.Fab")
		)
		(pad "1" smd custom
			(at 0 -0.4445 270)
			(size 0.1397 0.1397)
			(layers "F.Cu" "F.Mask" "F.Paste")
			(net "EXP_RESET_N")
			(options
				(clearance outline)
				(anchor circle)
			)
			(primitives
				(gr_poly
					(pts
						(arc
							(start -0.1778 -0.2794)
							(mid -0.249642 -0.249642)
							(end -0.2794 -0.1778)
						)
						(arc
							(start -0.2794 0.1778)
							(mid -0.249642 0.249642)
							(end -0.1778 0.2794)
						)
						(arc
							(start 0.1778 0.2794)
							(mid 0.249642 0.249642)
							(end 0.2794 0.1778)
						)
						(arc
							(start 0.2794 -0.1778)
							(mid 0.249642 -0.249642)
							(end 0.1778 -0.2794)
						)
					)
					(width 0)
					(fill yes)
				)
			)
		)
		(pad "2" smd custom
			(at 0 0.4445 270)
			(size 0.1397 0.1397)
			(layers "F.Cu" "F.Mask" "F.Paste")
			(net "EXP_RESET_R_U23_N")
			(options
				(clearance outline)
				(anchor circle)
			)
			(primitives
				(gr_poly
					(pts
						(arc
							(start -0.1778 -0.2794)
							(mid -0.249642 -0.249642)
							(end -0.2794 -0.1778)
						)
						(arc
							(start -0.2794 0.1778)
							(mid -0.249642 0.249642)
							(end -0.1778 0.2794)
						)
						(arc
							(start 0.1778 0.2794)
							(mid 0.249642 0.249642)
							(end 0.2794 0.1778)
						)
						(arc
							(start 0.2794 -0.1778)
							(mid 0.249642 -0.249642)
							(end 0.1778 -0.2794)
						)
					)
					(width 0)
					(fill yes)
				)
			)
		)
	)
	(footprint ""
		(layer "F.Cu")
		(at 52.8574 -41.8846)
		(property "Reference" "R480"
			(at 0 0 0)
			(layer "F.SilkS")
			(hide yes)
			(effects
				(font
					(size 1.27 1.27)
				)
			)
		)
		(property "Value" "0R3J-0-U-GP"
			(at -0.0254 -2.5146 0)
			(unlocked yes)
			(layer "F.Fab")
			(hide yes)
			(effects
				(font
					(size 1.016 1.016)
					(thickness 0.1524)
				)
			)
		)
		(property "Device Type" "R603H22"
			(at -0.0254 -4.0386 0)
			(unlocked yes)
			(layer "F.Fab")
			(hide yes)
			(effects
				(font
					(size 1.016 1.016)
					(thickness 0.1524)
				)
			)
		)
		(duplicate_pad_numbers_are_jumpers no)
		(fp_line
			(start -0.4826 0)
			(end -0.2032 0)
			(stroke
				(width 0.2032)
				(type default)
			)
			(layer "F.SilkS")
		)
		(fp_line
			(start 0.2032 0)
			(end 0.4826 0)
			(stroke
				(width 0.2032)
				(type default)
			)
			(layer "F.SilkS")
		)
		(fp_rect
			(start -0.5842 1.3335)
			(end 0.5842 -1.3335)
			(stroke
				(width 0)
				(type default)
			)
			(fill no)
			(layer "F.CrtYd")
		)
		(fp_rect
			(start -0.5842 1.3335)
			(end 0.5842 -1.3335)
			(stroke
				(width 0)
				(type default)
			)
			(fill no)
			(layer "F.Fab")
		)
		(pad "1" smd custom
			(at 0 -0.762)
			(size 0.2159 0.2159)
			(layers "F.Cu" "F.Mask" "F.Paste")
			(net "P0V9_BG")
			(options
				(clearance outline)
				(anchor circle)
			)
			(primitives
				(gr_poly
					(pts
						(arc
							(start -0.3302 -0.4318)
							(mid -0.402042 -0.402042)
							(end -0.4318 -0.3302)
						)
						(arc
							(start -0.4318 0.3302)
							(mid -0.402042 0.402042)
							(end -0.3302 0.4318)
						)
						(arc
							(start 0.3302 0.4318)
							(mid 0.402042 0.402042)
							(end 0.4318 0.3302)
						)
						(arc
							(start 0.4318 -0.3302)
							(mid 0.402042 -0.402042)
							(end 0.3302 -0.4318)
						)
					)
					(width 0)
					(fill yes)
				)
			)
		)
		(pad "2" smd custom
			(at 0 0.762)
			(size 0.2159 0.2159)
			(layers "F.Cu" "F.Mask" "F.Paste")
			(net "P0V9_DL")
			(options
				(clearance outline)
				(anchor circle)
			)
			(primitives
				(gr_poly
					(pts
						(arc
							(start -0.3302 -0.4318)
							(mid -0.402042 -0.402042)
							(end -0.4318 -0.3302)
						)
						(arc
							(start -0.4318 0.3302)
							(mid -0.402042 0.402042)
							(end -0.3302 0.4318)
						)
						(arc
							(start 0.3302 0.4318)
							(mid 0.402042 0.402042)
							(end 0.4318 0.3302)
						)
						(arc
							(start 0.4318 -0.3302)
							(mid 0.402042 -0.402042)
							(end 0.3302 -0.4318)
						)
					)
					(width 0)
					(fill yes)
				)
			)
		)
	)
	(footprint ""
		(layer "F.Cu")
		(at 15.195804 -63.535306 -90)
		(property "Reference" "C115"
			(at 0 0 270)
			(layer "F.SilkS")
			(hide yes)
			(effects
				(font
					(size 1.27 1.27)
				)
			)
		)
		(property "Value" "SC2D2U25V5KX-2-GP"
			(at -0.0762 -6.1214 270)
			(unlocked yes)
			(layer "F.Fab")
			(hide yes)
			(effects
				(font
					(size 1.016 1.016)
					(thickness 0.1524)
				)
			)
		)
		(property "Device Type" "C805H54"
			(at -0.0762 -8.1534 270)
			(unlocked yes)
			(layer "F.Fab")
			(hide yes)
			(effects
				(font
					(size 1.016 1.016)
					(thickness 0.1524)
				)
			)
		)
		(duplicate_pad_numbers_are_jumpers no)
		(fp_line
			(start 0.635 0)
			(end -0.635 0)
			(stroke
				(width 0.508)
				(type default)
			)
			(layer "F.SilkS")
		)
		(fp_rect
			(start -0.9652 1.778)
			(end 0.9652 -1.778)
			(stroke
				(width 0)
				(type default)
			)
			(fill no)
			(layer "F.CrtYd")
		)
		(fp_poly
			(pts
				(xy -0.9652 -1.778) (xy 0.9652 -1.778) (xy 0.9652 1.778) (xy -0.9652 1.778)
			)
			(stroke
				(width 0)
				(type default)
			)
			(fill no)
			(layer "F.Fab")
		)
		(pad "1" smd rect
			(at 0 -0.9652 270)
			(size 1.397 1.143)
			(layers "F.Cu" "F.Mask" "F.Paste")
			(net "MB0_HS_ENABLE")
		)
		(pad "2" smd rect
			(at 0 0.9652 270)
			(size 1.397 1.143)
			(layers "F.Cu" "F.Mask" "F.Paste")
			(net "GND")
		)
	)
	(footprint ""
		(layer "F.Cu")
		(at 170.563032 -56.089296)
		(property "Reference" "TP127"
			(at 0 0 0)
			(layer "F.SilkS")
			(hide yes)
			(effects
				(font
					(size 1.27 1.27)
				)
			)
		)
		(property "Value" "TPAD28-2-GP"
			(at -0.0127 -1.6637 0)
			(unlocked yes)
			(layer "F.Fab")
			(hide yes)
			(effects
				(font
					(size 1.016 1.016)
					(thickness 0.1524)
				)
			)
		)
		(property "Device Type" "TPAD28"
			(at -0.0127 -3.1877 0)
			(unlocked yes)
			(layer "F.Fab")
			(hide yes)
			(effects
				(font
					(size 1.016 1.016)
					(thickness 0.1524)
				)
			)
		)
		(duplicate_pad_numbers_are_jumpers no)
		(fp_poly
			(pts
				(arc
					(start 0.3556 0)
					(mid -0.3556 0)
					(end 0.3556 0)
				)
			)
			(stroke
				(width 0)
				(type default)
			)
			(fill no)
			(layer "F.CrtYd")
		)
		(fp_poly
			(pts
				(arc
					(start 0.6096 0)
					(mid -0.6096 0)
					(end 0.6096 0)
				)
			)
			(stroke
				(width 0)
				(type default)
			)
			(fill no)
			(layer "F.Fab")
		)
		(pad "1" smd circle
			(at 0 0)
			(size 0.7112 0.7112)
			(layers "F.Cu" "F.Mask" "F.Paste")
			(net "ICE1_TDO")
		)
	)
)
